(kicad_pcb
	(version 20260206)
	(generator "pcbnew")
	(generator_version "10.0")
	(general
		(thickness 1.6)
		(legacy_teardrops no)
	)
	(paper "A4")
	(title_block
		(title "03242023_DA0F0TMBIJ0_F0T_Motherboard_J_brd_V01_OCP.brd")
		(comment 1 "Grand Teton / footprints 1215-1219 of 6105")
	)
	(layers
		(0 "F.Cu" signal "TOP")
		(4 "In1.Cu" signal "GND")
		(6 "In2.Cu" signal "IN1")
		(8 "In3.Cu" signal "GND1")
		(10 "In4.Cu" signal "IN2")
		(12 "In5.Cu" signal "GND2")
		(14 "In6.Cu" signal "IN3")
		(16 "In7.Cu" signal "GND3")
		(18 "In8.Cu" signal "VCC")
		(20 "In9.Cu" signal "VCC1")
		(22 "In10.Cu" signal "GND4")
		(24 "In11.Cu" signal "IN4")
		(26 "In12.Cu" signal "GND5")
		(28 "In13.Cu" signal "IN5")
		(30 "In14.Cu" signal "GND6")
		(32 "In15.Cu" signal "IN6")
		(34 "In16.Cu" signal "GND7")
		(2 "B.Cu" signal "BOTTOM")
		(9 "F.Adhes" user "F.Adhesive")
		(11 "B.Adhes" user "B.Adhesive")
		(13 "F.Paste" user "Package Geometry/Pastemask Top")
		(15 "B.Paste" user "Package Geometry/Pastemask Bottom")
		(5 "F.SilkS" user "Ref Des/Silkscreen Top")
		(7 "B.SilkS" user "Ref Des/Silkscreen Bottom")
		(1 "F.Mask" user "Board Geometry/Soldermask Top")
		(3 "B.Mask" user "Board Geometry/Soldermask Bottom")
		(17 "Dwgs.User" user "User.Drawings")
		(19 "Cmts.User" user "User.Comments")
		(21 "Eco1.User" user "User.Eco1")
		(23 "Eco2.User" user "User.Eco2")
		(25 "Edge.Cuts" user "Board Geometry/Outline")
		(27 "Margin" user)
		(31 "F.CrtYd" user "Package Geometry/Place Bound Top")
		(29 "B.CrtYd" user "Package Geometry/Place Bound Bottom")
		(35 "F.Fab" user "Ref Des/Assembly Top")
		(33 "B.Fab" user "Ref Des/Assembly Bottom")
	)
	(footprint ""
		(layer "F.Cu")
		(at 140.843 -78.500478)
		(property "Reference" "U150"
			(at -1.16078 -1.98628 0)
			(unlocked yes)
			(layer "F.SilkS")
			(effects
				(font
					(size 0.7874 0.5842)
					(thickness 0.1524)
				)
				(justify left)
			)
		)
		(property "Value" ""
			(at 0 0 0)
			(layer "F.Fab")
			(effects
				(font
					(size 1.27 1.27)
				)
			)
		)
		(duplicate_pad_numbers_are_jumpers no)
		(fp_line
			(start -1.3462 -1.100074)
			(end -0.670052 -1.100074)
			(stroke
				(width 0.1524)
				(type default)
			)
			(layer "F.SilkS")
		)
		(fp_line
			(start -1.3462 1.100074)
			(end -1.3462 -1.100074)
			(stroke
				(width 0.1524)
				(type default)
			)
			(layer "F.SilkS")
		)
		(fp_line
			(start -0.670052 -1.100074)
			(end 0 -0.381)
			(stroke
				(width 0.1524)
				(type default)
			)
			(layer "F.SilkS")
		)
		(fp_line
			(start 0 -0.381)
			(end 0.670052 -1.100074)
			(stroke
				(width 0.1524)
				(type default)
			)
			(layer "F.SilkS")
		)
		(fp_line
			(start 0.670052 -1.100074)
			(end 1.3462 -1.100074)
			(stroke
				(width 0.1524)
				(type default)
			)
			(layer "F.SilkS")
		)
		(fp_line
			(start 1.3462 -1.100074)
			(end 1.3462 1.100074)
			(stroke
				(width 0.1524)
				(type default)
			)
			(layer "F.SilkS")
		)
		(fp_line
			(start 1.3462 1.100074)
			(end -1.3462 1.100074)
			(stroke
				(width 0.1524)
				(type default)
			)
			(layer "F.SilkS")
		)
		(fp_poly
			(pts
				(xy -1.524 -0.649986) (xy -2.286 -0.268986) (xy -2.286 -1.030986)
			)
			(stroke
				(width 0)
				(type default)
			)
			(fill yes)
			(layer "F.SilkS")
		)
		(fp_line
			(start -1.100074 -0.8001)
			(end -0.670052 -0.8001)
			(stroke
				(width 0.1)
				(type default)
			)
			(layer "F.Fab")
		)
		(fp_line
			(start -1.100074 0.8001)
			(end -1.100074 -0.8001)
			(stroke
				(width 0.1)
				(type default)
			)
			(layer "F.Fab")
		)
		(fp_line
			(start -0.670052 -1.100074)
			(end 0.670052 -1.100074)
			(stroke
				(width 0.1)
				(type default)
			)
			(layer "F.Fab")
		)
		(fp_line
			(start -0.670052 -0.8001)
			(end -0.670052 -1.100074)
			(stroke
				(width 0.1)
				(type default)
			)
			(layer "F.Fab")
		)
		(fp_line
			(start -0.670052 0.8001)
			(end -1.100074 0.8001)
			(stroke
				(width 0.1)
				(type default)
			)
			(layer "F.Fab")
		)
		(fp_line
			(start -0.670052 0.8001)
			(end -0.670052 -0.8001)
			(stroke
				(width 0.1)
				(type default)
			)
			(layer "F.Fab")
		)
		(fp_line
			(start -0.670052 1.100074)
			(end -0.670052 0.8001)
			(stroke
				(width 0.1)
				(type default)
			)
			(layer "F.Fab")
		)
		(fp_line
			(start 0.670052 -1.100074)
			(end 0.670052 -0.8001)
			(stroke
				(width 0.1)
				(type default)
			)
			(layer "F.Fab")
		)
		(fp_line
			(start 0.670052 -0.8001)
			(end 0.670052 0.8001)
			(stroke
				(width 0.1)
				(type default)
			)
			(layer "F.Fab")
		)
		(fp_line
			(start 0.670052 -0.8001)
			(end 1.100074 -0.8001)
			(stroke
				(width 0.1)
				(type default)
			)
			(layer "F.Fab")
		)
		(fp_line
			(start 0.670052 0.8001)
			(end 0.670052 1.100074)
			(stroke
				(width 0.1)
				(type default)
			)
			(layer "F.Fab")
		)
		(fp_line
			(start 0.670052 1.100074)
			(end -0.670052 1.100074)
			(stroke
				(width 0.1)
				(type default)
			)
			(layer "F.Fab")
		)
		(fp_line
			(start 1.100074 -0.8001)
			(end 1.100074 0.8001)
			(stroke
				(width 0.1)
				(type default)
			)
			(layer "F.Fab")
		)
		(fp_line
			(start 1.100074 0.8001)
			(end 0.670052 0.8001)
			(stroke
				(width 0.1)
				(type default)
			)
			(layer "F.Fab")
		)
		(fp_poly
			(pts
				(xy -1.524 -0.649986) (xy -2.286 -1.030986) (xy -2.286 -0.268986)
			)
			(stroke
				(width 0)
				(type default)
			)
			(fill yes)
			(layer "F.Fab")
		)
		(pad "1" smd rect
			(at -0.94996 -0.649986 270)
			(size 0.4064 0.508)
			(layers "F.Cu" "F.Mask" "F.Paste")
			(net "FM_PS_EN_PLD_R")
		)
		(pad "2" smd rect
			(at -0.94996 0 270)
			(size 0.4064 0.508)
			(layers "F.Cu" "F.Mask" "F.Paste")
			(net "GND")
		)
		(pad "3" smd rect
			(at -0.94996 0.649986 270)
			(size 0.4064 0.508)
			(layers "F.Cu" "F.Mask" "F.Paste")
			(net "NC_U150_A1")
		)
		(pad "4" smd rect
			(at 0.94996 0.649986 270)
			(size 0.4064 0.508)
			(layers "F.Cu" "F.Mask" "F.Paste")
			(net "NC_U150_B1")
		)
		(pad "5" smd rect
			(at 0.94996 0 270)
			(size 0.4064 0.508)
			(layers "F.Cu" "F.Mask" "F.Paste")
			(net "P3V3_AUX")
		)
		(pad "6" smd rect
			(at 0.94996 -0.649986 270)
			(size 0.4064 0.508)
			(layers "F.Cu" "F.Mask" "F.Paste")
			(net "FM_PS_EN_PLD_BUF1")
		)
	)
	(footprint ""
		(layer "F.Cu")
		(at 213.41588 -47.335948 90)
		(property "Reference" "R3589"
			(at 0 0 90)
			(layer "F.SilkS")
			(hide yes)
			(effects
				(font
					(size 1.27 1.27)
				)
			)
		)
		(property "Value" ""
			(at 0 0 90)
			(layer "F.Fab")
			(effects
				(font
					(size 1.27 1.27)
				)
			)
		)
		(duplicate_pad_numbers_are_jumpers no)
		(fp_line
			(start 0.7874 -0.4064)
			(end 0.7874 0.4064)
			(stroke
				(width 0.1524)
				(type default)
			)
			(layer "F.SilkS")
		)
		(fp_line
			(start -0.7874 -0.4064)
			(end 0.7874 -0.4064)
			(stroke
				(width 0.1524)
				(type default)
			)
			(layer "F.SilkS")
		)
		(fp_line
			(start 0.7874 0.4064)
			(end -0.7874 0.4064)
			(stroke
				(width 0.1524)
				(type default)
			)
			(layer "F.SilkS")
		)
		(fp_line
			(start -0.7874 0.4064)
			(end -0.7874 -0.4064)
			(stroke
				(width 0.1524)
				(type default)
			)
			(layer "F.SilkS")
		)
		(fp_line
			(start -0.12065 -0.305054)
			(end -0.12065 -0.2794)
			(stroke
				(width 0.1)
				(type default)
			)
			(layer "F.Fab")
		)
		(fp_line
			(start -0.67945 -0.305054)
			(end -0.12065 -0.305054)
			(stroke
				(width 0.1)
				(type default)
			)
			(layer "F.Fab")
		)
		(fp_line
			(start 0.67945 -0.3048)
			(end 0.67945 0.3048)
			(stroke
				(width 0.1)
				(type default)
			)
			(layer "F.Fab")
		)
		(fp_line
			(start 0.12065 -0.3048)
			(end 0.67945 -0.3048)
			(stroke
				(width 0.1)
				(type default)
			)
			(layer "F.Fab")
		)
		(fp_line
			(start 0.12065 -0.2794)
			(end 0.12065 -0.3048)
			(stroke
				(width 0.1)
				(type default)
			)
			(layer "F.Fab")
		)
		(fp_line
			(start -0.12065 -0.2794)
			(end 0.12065 -0.2794)
			(stroke
				(width 0.1)
				(type default)
			)
			(layer "F.Fab")
		)
		(fp_line
			(start 0.120396 0.2794)
			(end -0.12065 0.2794)
			(stroke
				(width 0.1)
				(type default)
			)
			(layer "F.Fab")
		)
		(fp_line
			(start -0.12065 0.2794)
			(end -0.12065 0.3048)
			(stroke
				(width 0.1)
				(type default)
			)
			(layer "F.Fab")
		)
		(fp_line
			(start 0.67945 0.3048)
			(end 0.120396 0.3048)
			(stroke
				(width 0.1)
				(type default)
			)
			(layer "F.Fab")
		)
		(fp_line
			(start 0.120396 0.3048)
			(end 0.120396 0.2794)
			(stroke
				(width 0.1)
				(type default)
			)
			(layer "F.Fab")
		)
		(fp_line
			(start -0.12065 0.3048)
			(end -0.67945 0.3048)
			(stroke
				(width 0.1)
				(type default)
			)
			(layer "F.Fab")
		)
		(fp_line
			(start -0.67945 0.3048)
			(end -0.67945 -0.305054)
			(stroke
				(width 0.1)
				(type default)
			)
			(layer "F.Fab")
		)
		(pad "1" smd circle
			(at -0.40005 0 90)
			(size 0 0)
			(layers "F.Cu" "F.Mask" "F.Paste")
			(net "SMB_INA230_3V3AUX_SDA")
		)
		(pad "2" smd circle
			(at 0.40005 0 90)
			(size 0 0)
			(layers "F.Cu" "F.Mask" "F.Paste")
			(net "SMB_INA230_2_3V3AUX_SDA_R")
		)
	)
	(footprint ""
		(layer "F.Cu")
		(at 106.86034 -417.362386 180)
		(property "Reference" "R4478"
			(at 0 0 180)
			(layer "F.SilkS")
			(hide yes)
			(effects
				(font
					(size 1.27 1.27)
				)
			)
		)
		(property "Value" ""
			(at 0 0 180)
			(layer "F.Fab")
			(effects
				(font
					(size 1.27 1.27)
				)
			)
		)
		(duplicate_pad_numbers_are_jumpers no)
		(fp_line
			(start 0.7874 0.4064)
			(end -0.7874 0.4064)
			(stroke
				(width 0.1524)
				(type default)
			)
			(layer "F.SilkS")
		)
		(fp_line
			(start 0.7874 -0.4064)
			(end 0.7874 0.4064)
			(stroke
				(width 0.1524)
				(type default)
			)
			(layer "F.SilkS")
		)
		(fp_line
			(start -0.7874 0.4064)
			(end -0.7874 -0.4064)
			(stroke
				(width 0.1524)
				(type default)
			)
			(layer "F.SilkS")
		)
		(fp_line
			(start -0.7874 -0.4064)
			(end 0.7874 -0.4064)
			(stroke
				(width 0.1524)
				(type default)
			)
			(layer "F.SilkS")
		)
		(fp_line
			(start 0.67945 0.3048)
			(end 0.120396 0.3048)
			(stroke
				(width 0.1)
				(type default)
			)
			(layer "F.Fab")
		)
		(fp_line
			(start 0.67945 -0.3048)
			(end 0.67945 0.3048)
			(stroke
				(width 0.1)
				(type default)
			)
			(layer "F.Fab")
		)
		(fp_line
			(start 0.12065 -0.2794)
			(end 0.12065 -0.3048)
			(stroke
				(width 0.1)
				(type default)
			)
			(layer "F.Fab")
		)
		(fp_line
			(start 0.12065 -0.3048)
			(end 0.67945 -0.3048)
			(stroke
				(width 0.1)
				(type default)
			)
			(layer "F.Fab")
		)
		(fp_line
			(start 0.120396 0.3048)
			(end 0.120396 0.2794)
			(stroke
				(width 0.1)
				(type default)
			)
			(layer "F.Fab")
		)
		(fp_line
			(start 0.120396 0.2794)
			(end -0.12065 0.2794)
			(stroke
				(width 0.1)
				(type default)
			)
			(layer "F.Fab")
		)
		(fp_line
			(start -0.12065 0.3048)
			(end -0.67945 0.3048)
			(stroke
				(width 0.1)
				(type default)
			)
			(layer "F.Fab")
		)
		(fp_line
			(start -0.12065 0.2794)
			(end -0.12065 0.3048)
			(stroke
				(width 0.1)
				(type default)
			)
			(layer "F.Fab")
		)
		(fp_line
			(start -0.12065 -0.2794)
			(end 0.12065 -0.2794)
			(stroke
				(width 0.1)
				(type default)
			)
			(layer "F.Fab")
		)
		(fp_line
			(start -0.12065 -0.305054)
			(end -0.12065 -0.2794)
			(stroke
				(width 0.1)
				(type default)
			)
			(layer "F.Fab")
		)
		(fp_line
			(start -0.67945 0.3048)
			(end -0.67945 -0.305054)
			(stroke
				(width 0.1)
				(type default)
			)
			(layer "F.Fab")
		)
		(fp_line
			(start -0.67945 -0.305054)
			(end -0.12065 -0.305054)
			(stroke
				(width 0.1)
				(type default)
			)
			(layer "F.Fab")
		)
		(pad "1" smd circle
			(at -0.40005 0 180)
			(size 0 0)
			(layers "F.Cu" "F.Mask" "F.Paste")
			(net "FM_9ZXL045_1_OE_N")
		)
		(pad "2" smd circle
			(at 0.40005 0 180)
			(size 0 0)
			(layers "F.Cu" "F.Mask" "F.Paste")
			(net "CLK_GPU_1_OE_N")
		)
	)
	(footprint ""
		(layer "F.Cu")
		(at 352.289618 -245.634002 -90)
		(property "Reference" "C401"
			(at 0 0 270)
			(layer "F.SilkS")
			(hide yes)
			(effects
				(font
					(size 1.27 1.27)
				)
			)
		)
		(property "Value" ""
			(at 0 0 270)
			(layer "F.Fab")
			(effects
				(font
					(size 1.27 1.27)
				)
			)
		)
		(duplicate_pad_numbers_are_jumpers no)
		(fp_line
			(start -0.7874 0.4064)
			(end -0.7874 -0.4064)
			(stroke
				(width 0.1524)
				(type default)
			)
			(layer "F.SilkS")
		)
		(fp_line
			(start 0.7874 0.4064)
			(end -0.7874 0.4064)
			(stroke
				(width 0.1524)
				(type default)
			)
			(layer "F.SilkS")
		)
		(fp_line
			(start -0.7874 -0.4064)
			(end 0.7874 -0.4064)
			(stroke
				(width 0.1524)
				(type default)
			)
			(layer "F.SilkS")
		)
		(fp_line
			(start 0.7874 -0.4064)
			(end 0.7874 0.4064)
			(stroke
				(width 0.1524)
				(type default)
			)
			(layer "F.SilkS")
		)
		(fp_line
			(start -0.67945 0.3048)
			(end -0.67945 -0.305054)
			(stroke
				(width 0.1)
				(type default)
			)
			(layer "F.Fab")
		)
		(fp_line
			(start -0.12065 0.3048)
			(end -0.67945 0.3048)
			(stroke
				(width 0.1)
				(type default)
			)
			(layer "F.Fab")
		)
		(fp_line
			(start 0.120396 0.3048)
			(end 0.120396 0.2794)
			(stroke
				(width 0.1)
				(type default)
			)
			(layer "F.Fab")
		)
		(fp_line
			(start 0.67945 0.3048)
			(end 0.120396 0.3048)
			(stroke
				(width 0.1)
				(type default)
			)
			(layer "F.Fab")
		)
		(fp_line
			(start -0.12065 0.2794)
			(end -0.12065 0.3048)
			(stroke
				(width 0.1)
				(type default)
			)
			(layer "F.Fab")
		)
		(fp_line
			(start 0.120396 0.2794)
			(end -0.12065 0.2794)
			(stroke
				(width 0.1)
				(type default)
			)
			(layer "F.Fab")
		)
		(fp_line
			(start -0.12065 -0.2794)
			(end 0.12065 -0.2794)
			(stroke
				(width 0.1)
				(type default)
			)
			(layer "F.Fab")
		)
		(fp_line
			(start 0.12065 -0.2794)
			(end 0.12065 -0.3048)
			(stroke
				(width 0.1)
				(type default)
			)
			(layer "F.Fab")
		)
		(fp_line
			(start 0.12065 -0.3048)
			(end 0.67945 -0.3048)
			(stroke
				(width 0.1)
				(type default)
			)
			(layer "F.Fab")
		)
		(fp_line
			(start 0.67945 -0.3048)
			(end 0.67945 0.3048)
			(stroke
				(width 0.1)
				(type default)
			)
			(layer "F.Fab")
		)
		(fp_line
			(start -0.67945 -0.305054)
			(end -0.12065 -0.305054)
			(stroke
				(width 0.1)
				(type default)
			)
			(layer "F.Fab")
		)
		(fp_line
			(start -0.12065 -0.305054)
			(end -0.12065 -0.2794)
			(stroke
				(width 0.1)
				(type default)
			)
			(layer "F.Fab")
		)
		(pad "1" smd circle
			(at -0.40005 0 270)
			(size 0 0)
			(layers "F.Cu" "F.Mask" "F.Paste")
			(net "PVCCD_HV_CPU0")
		)
		(pad "2" smd circle
			(at 0.40005 0 270)
			(size 0 0)
			(layers "F.Cu" "F.Mask" "F.Paste")
			(net "GND")
		)
	)
	(footprint ""
		(layer "F.Cu")
		(at 333.20228 -339.602572 90)
		(property "Reference" "PC248"
			(at 0 0 90)
			(layer "F.SilkS")
			(hide yes)
			(effects
				(font
					(size 1.27 1.27)
				)
			)
		)
		(property "Value" ""
			(at 0 0 90)
			(layer "F.Fab")
			(effects
				(font
					(size 1.27 1.27)
				)
			)
		)
		(duplicate_pad_numbers_are_jumpers no)
		(fp_line
			(start 0.7874 -0.4064)
			(end 0.7874 0.4064)
			(stroke
				(width 0.1524)
				(type default)
			)
			(layer "F.SilkS")
		)
		(fp_line
			(start -0.7874 -0.4064)
			(end 0.7874 -0.4064)
			(stroke
				(width 0.1524)
				(type default)
			)
			(layer "F.SilkS")
		)
		(fp_line
			(start 0.7874 0.4064)
			(end -0.7874 0.4064)
			(stroke
				(width 0.1524)
				(type default)
			)
			(layer "F.SilkS")
		)
		(fp_line
			(start -0.7874 0.4064)
			(end -0.7874 -0.4064)
			(stroke
				(width 0.1524)
				(type default)
			)
			(layer "F.SilkS")
		)
		(fp_line
			(start -0.12065 -0.305054)
			(end -0.12065 -0.2794)
			(stroke
				(width 0.1)
				(type default)
			)
			(layer "F.Fab")
		)
		(fp_line
			(start -0.67945 -0.305054)
			(end -0.12065 -0.305054)
			(stroke
				(width 0.1)
				(type default)
			)
			(layer "F.Fab")
		)
		(fp_line
			(start 0.67945 -0.3048)
			(end 0.67945 0.3048)
			(stroke
				(width 0.1)
				(type default)
			)
			(layer "F.Fab")
		)
		(fp_line
			(start 0.12065 -0.3048)
			(end 0.67945 -0.3048)
			(stroke
				(width 0.1)
				(type default)
			)
			(layer "F.Fab")
		)
		(fp_line
			(start 0.12065 -0.2794)
			(end 0.12065 -0.3048)
			(stroke
				(width 0.1)
				(type default)
			)
			(layer "F.Fab")
		)
		(fp_line
			(start -0.12065 -0.2794)
			(end 0.12065 -0.2794)
			(stroke
				(width 0.1)
				(type default)
			)
			(layer "F.Fab")
		)
		(fp_line
			(start 0.120396 0.2794)
			(end -0.12065 0.2794)
			(stroke
				(width 0.1)
				(type default)
			)
			(layer "F.Fab")
		)
		(fp_line
			(start -0.12065 0.2794)
			(end -0.12065 0.3048)
			(stroke
				(width 0.1)
				(type default)
			)
			(layer "F.Fab")
		)
		(fp_line
			(start 0.67945 0.3048)
			(end 0.120396 0.3048)
			(stroke
				(width 0.1)
				(type default)
			)
			(layer "F.Fab")
		)
		(fp_line
			(start 0.120396 0.3048)
			(end 0.120396 0.2794)
			(stroke
				(width 0.1)
				(type default)
			)
			(layer "F.Fab")
		)
		(fp_line
			(start -0.12065 0.3048)
			(end -0.67945 0.3048)
			(stroke
				(width 0.1)
				(type default)
			)
			(layer "F.Fab")
		)
		(fp_line
			(start -0.67945 0.3048)
			(end -0.67945 -0.305054)
			(stroke
				(width 0.1)
				(type default)
			)
			(layer "F.Fab")
		)
		(pad "1" smd circle
			(at -0.40005 0 90)
			(size 0 0)
			(layers "F.Cu" "F.Mask" "F.Paste")
			(net "PVCCIN_CPU0_VDD6")
		)
		(pad "2" smd circle
			(at 0.40005 0 90)
			(size 0 0)
			(layers "F.Cu" "F.Mask" "F.Paste")
			(net "GND")
		)
	)
)
